# BARRELEYE_G2-FPDB_POST-EVT-HW-EBOM-X00_20161123-add_2nd_source_X08-20161215-Final-b.xls — Component Qual Tracker (bom)
|  |  |  |  |  |  |  |  | Part to be included on following build: |  |  |  |  |  |
| Item No. | Part Group | Single/Sole/Multi | Item Description | ODM P/N | Customer PN | Vendor | Vendor P/N | X00 Build | X01 Build | X02 Build | Qual Build | Qualification Target Date | Qualification Complete Date |
|  | VR Controllers |  |  |  |  | Vendor #1 |  |  |  |  |  |  |  |
|  |  |  |  |  |  | Vendor #2 |  |  |  |  |  |  |  |
|  | FETS |  |  |  |  | Vendor #1 |  |  |  |  |  |  |  |
|  |  |  |  |  |  | Vendor #2 |  |  |  |  |  |  |  |
|  | INDUCTORS |  |  |  |  | Vendor #1 |  |  |  |  |  |  |  |
|  |  |  |  |  |  | Vendor #2 |  |  |  |  |  |  |  |
|  | VREG CAPS |  |  |  |  | Vendor #1 |  |  |  |  |  |  |  |
|  |  |  |  |  |  | Vendor #2 |  |  |  |  |  |  |  |
|  | CRYSTALS |  |  |  |  | Vendor #1 |  |  |  |  |  |  |  |
|  |  |  |  |  |  | Vendor #2 |  |  |  |  |  |  |  |
|  | CONNECTORS |  |  |  |  | Vendor #1 |  |  |  |  |  |  |  |
|  |  |  |  |  |  | Vendor #2 |  |  |  |  |  |  |  |
|  | IC'S |  |  |  |  | Vendor #1 |  |  |  |  |  |  |  |
|  |  |  |  |  |  | Vendor #2 |  |  |  |  |  |  |  |
|  | MISC. |  |  |  |  | Vendor #1 |  |  |  |  |  |  |  |
|  | (HEATSINKS) |  |  |  |  | Vendor #2 |  |  |  |  |  |  |  |
